# T6G (Grand Teton) — schematic netlist excerpt (pin names and nets, part order shuffled) for the footprints in the layout excerpt that follows; sources: Cadence DE-HDL packaged netlist, KiCad conversion of 04192023_DAF0TMB3IC0_F0TG_MB_C_brd_V02_OCP.brd

L23  Q_INDUCTOR  100NH/16A IND  pkg SMLF  page 312 : \1\ = P0V9_CPU0_RT_2D ; \2\ = P0V9_CPU0_RT3_2A
R6045  Q_RES  4.7K 5% EMPTY  pkg 0402LF  page 134 : A = P12V_OCP_EN_1_R ; B = GND
R222  Q_RES  0 5% CHIP  pkg 0402LF  page 82 : A = CPU0_SP5R3 ; B = FM_CPU0_SP5R3

(kicad_pcb
	(version 20260206)
	(generator "pcbnew")
	(generator_version "10.0")
	(general
		(thickness 1.6)
		(legacy_teardrops no)
	)
	(paper "A4")
	(title_block
		(title "04192023_DAF0TMB3IC0_F0TG_MB_C_brd_V02_OCP.brd")
		(comment 1 "Grand Teton / footprints 3488-3490 of 8354")
	)
	(layers
		(0 "F.Cu" signal "TOP")
		(4 "In1.Cu" signal "GND")
		(6 "In2.Cu" signal "IN1")
		(8 "In3.Cu" signal "GND1")
		(10 "In4.Cu" signal "IN2")
		(12 "In5.Cu" signal "GND2")
		(14 "In6.Cu" signal "IN3")
		(16 "In7.Cu" signal "GND3")
		(18 "In8.Cu" signal "VCC")
		(20 "In9.Cu" signal "VCC1")
		(22 "In10.Cu" signal "GND4")
		(24 "In11.Cu" signal "IN4")
		(26 "In12.Cu" signal "GND5")
		(28 "In13.Cu" signal "IN5")
		(30 "In14.Cu" signal "GND6")
		(32 "In15.Cu" signal "IN6")
		(34 "In16.Cu" signal "GND7")
		(2 "B.Cu" signal "BOTTOM")
		(9 "F.Adhes" user "F.Adhesive")
		(11 "B.Adhes" user "B.Adhesive")
		(13 "F.Paste" user "Package Geometry/Pastemask Top")
		(15 "B.Paste" user "Package Geometry/Pastemask Bottom")
		(5 "F.SilkS" user "Ref Des/Silkscreen Top")
		(7 "B.SilkS" user "Ref Des/Silkscreen Bottom")
		(1 "F.Mask" user "Board Geometry/Soldermask Top")
		(3 "B.Mask" user "Board Geometry/Soldermask Bottom")
		(17 "Dwgs.User" user "User.Drawings")
		(19 "Cmts.User" user "User.Comments")
		(21 "Eco1.User" user "User.Eco1")
		(23 "Eco2.User" user "User.Eco2")
		(25 "Edge.Cuts" user "Board Geometry/Outline")
		(27 "Margin" user)
		(31 "F.CrtYd" user "Package Geometry/Place Bound Top")
		(29 "B.CrtYd" user "Package Geometry/Place Bound Bottom")
		(35 "F.Fab" user "Ref Des/Assembly Top")
		(33 "B.Fab" user "Ref Des/Assembly Bottom")
	)
	(footprint ""
		(layer "F.Cu")
		(at 192.913 -100.294948 90)
		(property "Reference" "R222"
			(at 0 0 90)
			(layer "F.SilkS")
			(hide yes)
			(effects
				(font
					(size 1.27 1.27)
				)
			)
		)
		(property "Value" ""
			(at 0 0 90)
			(layer "F.Fab")
			(effects
				(font
					(size 1.27 1.27)
				)
			)
		)
		(duplicate_pad_numbers_are_jumpers no)
		(fp_line
			(start 0.7874 -0.4064)
			(end 0.7874 0.4064)
			(stroke
				(width 0.1524)
				(type default)
			)
			(layer "F.SilkS")
		)
		(fp_line
			(start -0.7874 -0.4064)
			(end 0.7874 -0.4064)
			(stroke
				(width 0.1524)
				(type default)
			)
			(layer "F.SilkS")
		)
		(fp_line
			(start 0.7874 0.4064)
			(end -0.7874 0.4064)
			(stroke
				(width 0.1524)
				(type default)
			)
			(layer "F.SilkS")
		)
		(fp_line
			(start -0.7874 0.4064)
			(end -0.7874 -0.4064)
			(stroke
				(width 0.1524)
				(type default)
			)
			(layer "F.SilkS")
		)
		(fp_line
			(start -0.12065 -0.305054)
			(end -0.12065 -0.2794)
			(stroke
				(width 0.1)
				(type default)
			)
			(layer "F.Fab")
		)
		(fp_line
			(start -0.67945 -0.305054)
			(end -0.12065 -0.305054)
			(stroke
				(width 0.1)
				(type default)
			)
			(layer "F.Fab")
		)
		(fp_line
			(start 0.67945 -0.3048)
			(end 0.67945 0.3048)
			(stroke
				(width 0.1)
				(type default)
			)
			(layer "F.Fab")
		)
		(fp_line
			(start 0.12065 -0.3048)
			(end 0.67945 -0.3048)
			(stroke
				(width 0.1)
				(type default)
			)
			(layer "F.Fab")
		)
		(fp_line
			(start 0.12065 -0.2794)
			(end 0.12065 -0.3048)
			(stroke
				(width 0.1)
				(type default)
			)
			(layer "F.Fab")
		)
		(fp_line
			(start -0.12065 -0.2794)
			(end 0.12065 -0.2794)
			(stroke
				(width 0.1)
				(type default)
			)
			(layer "F.Fab")
		)
		(fp_line
			(start 0.120396 0.2794)
			(end -0.12065 0.2794)
			(stroke
				(width 0.1)
				(type default)
			)
			(layer "F.Fab")
		)
		(fp_line
			(start -0.12065 0.2794)
			(end -0.12065 0.3048)
			(stroke
				(width 0.1)
				(type default)
			)
			(layer "F.Fab")
		)
		(fp_line
			(start 0.67945 0.3048)
			(end 0.120396 0.3048)
			(stroke
				(width 0.1)
				(type default)
			)
			(layer "F.Fab")
		)
		(fp_line
			(start 0.120396 0.3048)
			(end 0.120396 0.2794)
			(stroke
				(width 0.1)
				(type default)
			)
			(layer "F.Fab")
		)
		(fp_line
			(start -0.12065 0.3048)
			(end -0.67945 0.3048)
			(stroke
				(width 0.1)
				(type default)
			)
			(layer "F.Fab")
		)
		(fp_line
			(start -0.67945 0.3048)
			(end -0.67945 -0.305054)
			(stroke
				(width 0.1)
				(type default)
			)
			(layer "F.Fab")
		)
		(pad "1" smd circle
			(at -0.40005 0 90)
			(size 0 0)
			(layers "F.Cu" "F.Mask" "F.Paste")
			(net "CPU0_SP5R3")
		)
		(pad "2" smd circle
			(at 0.40005 0 90)
			(size 0 0)
			(layers "F.Cu" "F.Mask" "F.Paste")
			(net "FM_CPU0_SP5R3")
		)
	)
	(footprint ""
		(layer "F.Cu")
		(at 363.72292 -400.903694)
		(property "Reference" "L23"
			(at -2.3876 -2.969768 0)
			(unlocked yes)
			(layer "F.SilkS")
			(effects
				(font
					(size 0.7874 0.5842)
					(thickness 0.1524)
				)
				(justify left)
			)
		)
		(property "Value" ""
			(at 0 0 0)
			(layer "F.Fab")
			(effects
				(font
					(size 1.27 1.27)
				)
			)
		)
		(duplicate_pad_numbers_are_jumpers no)
		(fp_line
			(start -2.249932 -2.249932)
			(end 2.249932 -2.249932)
			(stroke
				(width 0.1524)
				(type default)
			)
			(layer "F.SilkS")
		)
		(fp_line
			(start -2.249932 -1.3843)
			(end -2.249932 -2.249932)
			(stroke
				(width 0.1524)
				(type default)
			)
			(layer "F.SilkS")
		)
		(fp_line
			(start -2.249932 2.249932)
			(end -2.249932 1.3843)
			(stroke
				(width 0.1524)
				(type default)
			)
			(layer "F.SilkS")
		)
		(fp_line
			(start 2.249932 -2.249932)
			(end 2.249932 -1.3843)
			(stroke
				(width 0.1524)
				(type default)
			)
			(layer "F.SilkS")
		)
		(fp_line
			(start 2.249932 1.3843)
			(end 2.249932 2.249932)
			(stroke
				(width 0.1524)
				(type default)
			)
			(layer "F.SilkS")
		)
		(fp_line
			(start 2.249932 2.249932)
			(end -2.249932 2.249932)
			(stroke
				(width 0.1524)
				(type default)
			)
			(layer "F.SilkS")
		)
		(fp_line
			(start -2.249932 -2.249932)
			(end 2.249932 -2.249932)
			(stroke
				(width 0.1)
				(type default)
			)
			(layer "F.Fab")
		)
		(fp_line
			(start -2.249932 2.249932)
			(end -2.249932 -2.249932)
			(stroke
				(width 0.1)
				(type default)
			)
			(layer "F.Fab")
		)
		(fp_line
			(start 2.249932 -2.249932)
			(end 2.249932 2.249932)
			(stroke
				(width 0.1)
				(type default)
			)
			(layer "F.Fab")
		)
		(fp_line
			(start 2.249932 2.249932)
			(end -2.249932 2.249932)
			(stroke
				(width 0.1)
				(type default)
			)
			(layer "F.Fab")
		)
		(pad "1" smd rect
			(at -1.82499 0)
			(size 1.0668 2.5146)
			(layers "F.Cu" "F.Mask" "F.Paste")
			(net "P0V9_CPU0_RT_2D")
		)
		(pad "2" smd rect
			(at 1.82499 0)
			(size 1.0668 2.5146)
			(layers "F.Cu" "F.Mask" "F.Paste")
			(net "P0V9_CPU0_RT3_2A")
		)
	)
	(footprint ""
		(layer "F.Cu")
		(at 468.957914 -41.105836)
		(property "Reference" "R6045"
			(at 0 0 0)
			(layer "F.SilkS")
			(hide yes)
			(effects
				(font
					(size 1.27 1.27)
				)
			)
		)
		(property "Value" ""
			(at 0 0 0)
			(layer "F.Fab")
			(effects
				(font
					(size 1.27 1.27)
				)
			)
		)
		(duplicate_pad_numbers_are_jumpers no)
		(fp_line
			(start -0.7874 -0.4064)
			(end 0.7874 -0.4064)
			(stroke
				(width 0.1524)
				(type default)
			)
			(layer "F.SilkS")
		)
		(fp_line
			(start -0.7874 0.4064)
			(end -0.7874 -0.4064)
			(stroke
				(width 0.1524)
				(type default)
			)
			(layer "F.SilkS")
		)
		(fp_line
			(start 0.7874 -0.4064)
			(end 0.7874 0.4064)
			(stroke
				(width 0.1524)
				(type default)
			)
			(layer "F.SilkS")
		)
		(fp_line
			(start 0.7874 0.4064)
			(end -0.7874 0.4064)
			(stroke
				(width 0.1524)
				(type default)
			)
			(layer "F.SilkS")
		)
		(fp_line
			(start -0.67945 -0.305054)
			(end -0.12065 -0.305054)
			(stroke
				(width 0.1)
				(type default)
			)
			(layer "F.Fab")
		)
		(fp_line
			(start -0.67945 0.3048)
			(end -0.67945 -0.305054)
			(stroke
				(width 0.1)
				(type default)
			)
			(layer "F.Fab")
		)
		(fp_line
			(start -0.12065 -0.305054)
			(end -0.12065 -0.2794)
			(stroke
				(width 0.1)
				(type default)
			)
			(layer "F.Fab")
		)
		(fp_line
			(start -0.12065 -0.2794)
			(end 0.12065 -0.2794)
			(stroke
				(width 0.1)
				(type default)
			)
			(layer "F.Fab")
		)
		(fp_line
			(start -0.12065 0.2794)
			(end -0.12065 0.3048)
			(stroke
				(width 0.1)
				(type default)
			)
			(layer "F.Fab")
		)
		(fp_line
			(start -0.12065 0.3048)
			(end -0.67945 0.3048)
			(stroke
				(width 0.1)
				(type default)
			)
			(layer "F.Fab")
		)
		(fp_line
			(start 0.120396 0.2794)
			(end -0.12065 0.2794)
			(stroke
				(width 0.1)
				(type default)
			)
			(layer "F.Fab")
		)
		(fp_line
			(start 0.120396 0.3048)
			(end 0.120396 0.2794)
			(stroke
				(width 0.1)
				(type default)
			)
			(layer "F.Fab")
		)
		(fp_line
			(start 0.12065 -0.3048)
			(end 0.67945 -0.3048)
			(stroke
				(width 0.1)
				(type default)
			)
			(layer "F.Fab")
		)
		(fp_line
			(start 0.12065 -0.2794)
			(end 0.12065 -0.3048)
			(stroke
				(width 0.1)
				(type default)
			)
			(layer "F.Fab")
		)
		(fp_line
			(start 0.67945 -0.3048)
			(end 0.67945 0.3048)
			(stroke
				(width 0.1)
				(type default)
			)
			(layer "F.Fab")
		)
		(fp_line
			(start 0.67945 0.3048)
			(end 0.120396 0.3048)
			(stroke
				(width 0.1)
				(type default)
			)
			(layer "F.Fab")
		)
		(pad "1" smd circle
			(at -0.40005 0)
			(size 0 0)
			(layers "F.Cu" "F.Mask" "F.Paste")
			(net "P12V_OCP_EN_1_R")
		)
		(pad "2" smd circle
			(at 0.40005 0)
			(size 0 0)
			(layers "F.Cu" "F.Mask" "F.Paste")
			(net "GND")
		)
	)
)
